(kicad_pcb
	(version 20260206)
	(generator "pcbnew")
	(generator_version "10.0")
	(general
		(thickness 1.6)
		(legacy_teardrops no)
	)
	(paper "A4")
	(title_block
		(title "v1-chassis-manager — T6M_CM_d_v01_1031_1645.brd")
		(comment 1 "Open CloudServer (Microsoft) / footprints 1059-1068 of 2512")
	)
	(layers
		(0 "F.Cu" signal "TOP")
		(4 "In1.Cu" signal "GND1")
		(6 "In2.Cu" signal "IN1")
		(8 "In3.Cu" signal "VCC1")
		(10 "In4.Cu" signal "VCC2")
		(12 "In5.Cu" signal "GND2")
		(14 "In6.Cu" signal "IN2")
		(16 "In7.Cu" signal "IN3")
		(18 "In8.Cu" signal "GND3")
		(2 "B.Cu" signal "BOTTOM")
		(9 "F.Adhes" user "F.Adhesive")
		(11 "B.Adhes" user "B.Adhesive")
		(13 "F.Paste" user "Package Geometry/Pastemask Top")
		(15 "B.Paste" user "Package Geometry/Pastemask Bottom")
		(5 "F.SilkS" user "Ref Des/Silkscreen Top")
		(7 "B.SilkS" user "Ref Des/Silkscreen Bottom")
		(1 "F.Mask" user "Board Geometry/Soldermask Top")
		(3 "B.Mask" user "Board Geometry/Soldermask Bottom")
		(17 "Dwgs.User" user "User.Drawings")
		(19 "Cmts.User" user "User.Comments")
		(21 "Eco1.User" user "User.Eco1")
		(23 "Eco2.User" user "User.Eco2")
		(25 "Edge.Cuts" user "Board Geometry/Outline")
		(27 "Margin" user)
		(31 "F.CrtYd" user "Package Geometry/Place Bound Top")
		(29 "B.CrtYd" user "Package Geometry/Place Bound Bottom")
		(35 "F.Fab" user "Ref Des/Assembly Top")
		(33 "B.Fab" user "Ref Des/Assembly Bottom")
	)
	(footprint ""
		(layer "F.Cu")
		(at 62.161166 -96.709992 90)
		(property "Reference" "R57"
			(at -54.98719 28.524962 90)
			(unlocked yes)
			(layer "F.SilkS")
			(effects
				(font
					(size 0.7874 0.5842)
					(thickness 0.1524)
				)
				(justify left)
			)
		)
		(property "Value" ""
			(at 0 0 90)
			(layer "F.Fab")
			(effects
				(font
					(size 1.27 1.27)
				)
			)
		)
		(duplicate_pad_numbers_are_jumpers no)
		(fp_line
			(start 0.7874 -0.4064)
			(end 0.7874 0.4064)
			(stroke
				(width 0.1524)
				(type default)
			)
			(layer "F.SilkS")
		)
		(fp_line
			(start -0.7874 -0.4064)
			(end 0.7874 -0.4064)
			(stroke
				(width 0.1524)
				(type default)
			)
			(layer "F.SilkS")
		)
		(fp_line
			(start 0.7874 0.4064)
			(end -0.7874 0.4064)
			(stroke
				(width 0.1524)
				(type default)
			)
			(layer "F.SilkS")
		)
		(fp_line
			(start -0.7874 0.4064)
			(end -0.7874 -0.4064)
			(stroke
				(width 0.1524)
				(type default)
			)
			(layer "F.SilkS")
		)
		(fp_poly
			(pts
				(xy -0.508 0.2794) (xy -0.508 0.2286) (xy -0.635 0.2286) (xy -0.635 -0.254) (xy -0.5334 -0.254)
				(xy -0.5334 -0.2794) (xy 0.5334 -0.2794) (xy 0.5334 -0.254) (xy 0.635 -0.254) (xy 0.635 0.254) (xy 0.5334 0.254)
				(xy 0.5334 0.2794)
			)
			(stroke
				(width 0)
				(type default)
			)
			(fill no)
			(layer "F.CrtYd")
		)
		(pad "1" smd rect
			(at 0.40005 0 90)
			(size 0.4572 0.508)
			(layers "F.Cu" "F.Mask" "F.Paste")
			(net "SPI_CPU_NODE1_CS0_L")
		)
		(pad "2" smd rect
			(at -0.40005 0 90)
			(size 0.4572 0.508)
			(layers "F.Cu" "F.Mask" "F.Paste")
			(net "SPI_CPU_NODE1_CS0_R_L")
		)
	)
	(footprint ""
		(layer "F.Cu")
		(at 40.177974 -4.07035 90)
		(property "Reference" "PC31"
			(at -3.490722 -12.492482 90)
			(unlocked yes)
			(layer "F.SilkS")
			(effects
				(font
					(size 0.7874 0.5842)
					(thickness 0.1524)
				)
				(justify left)
			)
		)
		(property "Value" ""
			(at 0 0 90)
			(layer "F.Fab")
			(effects
				(font
					(size 1.27 1.27)
				)
			)
		)
		(duplicate_pad_numbers_are_jumpers no)
		(fp_line
			(start 0.7874 -0.4064)
			(end 0.7874 0.4064)
			(stroke
				(width 0.1524)
				(type default)
			)
			(layer "F.SilkS")
		)
		(fp_line
			(start -0.7874 -0.4064)
			(end 0.7874 -0.4064)
			(stroke
				(width 0.1524)
				(type default)
			)
			(layer "F.SilkS")
		)
		(fp_line
			(start 0 0.381)
			(end 0 -0.381)
			(stroke
				(width 0.1524)
				(type default)
			)
			(layer "F.SilkS")
		)
		(fp_line
			(start 0.7874 0.4064)
			(end -0.7874 0.4064)
			(stroke
				(width 0.1524)
				(type default)
			)
			(layer "F.SilkS")
		)
		(fp_line
			(start -0.7874 0.4064)
			(end -0.7874 -0.4064)
			(stroke
				(width 0.1524)
				(type default)
			)
			(layer "F.SilkS")
		)
		(fp_poly
			(pts
				(xy -0.5334 0.254) (xy -0.635 0.254) (xy -0.635 0.2286) (xy -0.635 -0.254) (xy -0.5334 -0.254) (xy -0.5334 -0.2794)
				(xy 0.5334 -0.2794) (xy 0.5334 -0.254) (xy 0.635 -0.254) (xy 0.635 0.254) (xy 0.5334 0.254) (xy 0.5334 0.2794)
				(xy -0.508 0.2794) (xy -0.5334 0.2794)
			)
			(stroke
				(width 0)
				(type default)
			)
			(fill no)
			(layer "F.CrtYd")
		)
		(pad "1" smd rect
			(at 0.40005 0 90)
			(size 0.4572 0.508)
			(layers "F.Cu" "F.Mask" "F.Paste")
			(net "FM_CPLD_NODE1_PVDDR_STB_EN")
		)
		(pad "2" smd rect
			(at -0.40005 0 90)
			(size 0.4572 0.508)
			(layers "F.Cu" "F.Mask" "F.Paste")
			(net "GND")
		)
	)
	(footprint ""
		(layer "F.Cu")
		(at 99.938078 -150.328122)
		(property "Reference" "PC32"
			(at -1.988566 2.731008 0)
			(unlocked yes)
			(layer "F.SilkS")
			(effects
				(font
					(size 0.7874 0.5842)
					(thickness 0.1524)
				)
				(justify left)
			)
		)
		(property "Value" ""
			(at 0 0 0)
			(layer "F.Fab")
			(effects
				(font
					(size 1.27 1.27)
				)
			)
		)
		(duplicate_pad_numbers_are_jumpers no)
		(fp_line
			(start -2.2098 -0.9398)
			(end 2.2098 -0.9398)
			(stroke
				(width 0.1524)
				(type default)
			)
			(layer "F.SilkS")
		)
		(fp_line
			(start -2.2098 0.9398)
			(end -2.2098 -0.9398)
			(stroke
				(width 0.1524)
				(type default)
			)
			(layer "F.SilkS")
		)
		(fp_line
			(start 0 -0.9398)
			(end 0 0.9398)
			(stroke
				(width 0.1524)
				(type default)
			)
			(layer "F.SilkS")
		)
		(fp_line
			(start 2.2098 -0.9398)
			(end 2.2098 0.9398)
			(stroke
				(width 0.1524)
				(type default)
			)
			(layer "F.SilkS")
		)
		(fp_line
			(start 2.2098 0.9398)
			(end -2.2098 0.9398)
			(stroke
				(width 0.1524)
				(type default)
			)
			(layer "F.SilkS")
		)
		(fp_poly
			(pts
				(xy -1.6764 0.889) (xy -1.6764 0.7874) (xy -2.0574 0.7874) (xy -2.0574 -0.7874) (xy -1.6764 -0.7874)
				(xy -1.6764 -0.9398) (xy 1.6764 -0.9398) (xy 1.6764 -0.7874) (xy 2.0574 -0.7874) (xy 2.0574 0.7874)
				(xy 1.6764 0.7874) (xy 1.6764 0.9398) (xy -1.6764 0.9398)
			)
			(stroke
				(width 0)
				(type default)
			)
			(fill no)
			(layer "F.CrtYd")
		)
		(fp_line
			(start -1.700022 -0.899922)
			(end 1.700022 -0.899922)
			(stroke
				(width 0.1)
				(type default)
			)
			(layer "F.Fab")
		)
		(fp_line
			(start -1.700022 0.899922)
			(end -1.700022 -0.899922)
			(stroke
				(width 0.1)
				(type default)
			)
			(layer "F.Fab")
		)
		(fp_line
			(start 1.700022 -0.899922)
			(end 1.700022 0.899922)
			(stroke
				(width 0.1)
				(type default)
			)
			(layer "F.Fab")
		)
		(fp_line
			(start 1.700022 0.899922)
			(end -1.700022 0.899922)
			(stroke
				(width 0.1)
				(type default)
			)
			(layer "F.Fab")
		)
		(pad "1" smd rect
			(at 1.4732 0)
			(size 1.1684 1.5748)
			(layers "F.Cu" "F.Mask" "F.Paste")
			(net "P12V_AUX")
		)
		(pad "2" smd rect
			(at -1.4732 0)
			(size 1.1684 1.5748)
			(layers "F.Cu" "F.Mask" "F.Paste")
			(net "GND")
		)
	)
	(footprint ""
		(layer "F.Cu")
		(at 36.707572 -74.418698 180)
		(property "Reference" "R150"
			(at 5.396484 -0.103124 0)
			(unlocked yes)
			(layer "F.SilkS")
			(effects
				(font
					(size 0.7874 0.5842)
					(thickness 0.1524)
				)
				(justify left)
			)
		)
		(property "Value" ""
			(at 0 0 180)
			(layer "F.Fab")
			(effects
				(font
					(size 1.27 1.27)
				)
			)
		)
		(duplicate_pad_numbers_are_jumpers no)
		(fp_line
			(start 0.7874 0.4064)
			(end -0.7874 0.4064)
			(stroke
				(width 0.1524)
				(type default)
			)
			(layer "F.SilkS")
		)
		(fp_line
			(start 0.7874 -0.4064)
			(end 0.7874 0.4064)
			(stroke
				(width 0.1524)
				(type default)
			)
			(layer "F.SilkS")
		)
		(fp_line
			(start -0.7874 0.4064)
			(end -0.7874 -0.4064)
			(stroke
				(width 0.1524)
				(type default)
			)
			(layer "F.SilkS")
		)
		(fp_line
			(start -0.7874 -0.4064)
			(end 0.7874 -0.4064)
			(stroke
				(width 0.1524)
				(type default)
			)
			(layer "F.SilkS")
		)
		(fp_poly
			(pts
				(xy -0.508 0.2794) (xy -0.508 0.2286) (xy -0.635 0.2286) (xy -0.635 -0.254) (xy -0.5334 -0.254)
				(xy -0.5334 -0.2794) (xy 0.5334 -0.2794) (xy 0.5334 -0.254) (xy 0.635 -0.254) (xy 0.635 0.254) (xy 0.5334 0.254)
				(xy 0.5334 0.2794)
			)
			(stroke
				(width 0)
				(type default)
			)
			(fill no)
			(layer "F.CrtYd")
		)
		(pad "1" smd rect
			(at 0.40005 0 180)
			(size 0.4572 0.508)
			(layers "F.Cu" "F.Mask" "F.Paste")
			(net "P1V5_NODE1")
		)
		(pad "2" smd rect
			(at -0.40005 0 180)
			(size 0.4572 0.508)
			(layers "F.Cu" "F.Mask" "F.Paste")
			(net "P1V5_NODE1_AJ21")
		)
	)
	(footprint ""
		(layer "F.Cu")
		(at 108.31576 -185.205624 -90)
		(property "Reference" "R893"
			(at -4.768088 -0.724408 90)
			(unlocked yes)
			(layer "F.SilkS")
			(effects
				(font
					(size 0.7874 0.5842)
					(thickness 0.1524)
				)
				(justify left)
			)
		)
		(property "Value" ""
			(at 0 0 270)
			(layer "F.Fab")
			(effects
				(font
					(size 1.27 1.27)
				)
			)
		)
		(duplicate_pad_numbers_are_jumpers no)
		(fp_line
			(start -0.7874 0.4064)
			(end -0.7874 -0.4064)
			(stroke
				(width 0.1524)
				(type default)
			)
			(layer "F.SilkS")
		)
		(fp_line
			(start 0.7874 0.4064)
			(end -0.7874 0.4064)
			(stroke
				(width 0.1524)
				(type default)
			)
			(layer "F.SilkS")
		)
		(fp_line
			(start -0.7874 -0.4064)
			(end 0.7874 -0.4064)
			(stroke
				(width 0.1524)
				(type default)
			)
			(layer "F.SilkS")
		)
		(fp_line
			(start 0.7874 -0.4064)
			(end 0.7874 0.4064)
			(stroke
				(width 0.1524)
				(type default)
			)
			(layer "F.SilkS")
		)
		(fp_poly
			(pts
				(xy -0.508 0.2794) (xy -0.508 0.2286) (xy -0.635 0.2286) (xy -0.635 -0.254) (xy -0.5334 -0.254)
				(xy -0.5334 -0.2794) (xy 0.5334 -0.2794) (xy 0.5334 -0.254) (xy 0.635 -0.254) (xy 0.635 0.254) (xy 0.5334 0.254)
				(xy 0.5334 0.2794)
			)
			(stroke
				(width 0)
				(type default)
			)
			(fill no)
			(layer "F.CrtYd")
		)
		(pad "1" smd rect
			(at 0.40005 0 270)
			(size 0.4572 0.508)
			(layers "F.Cu" "F.Mask" "F.Paste")
			(net "T6_NODE4_EN")
		)
		(pad "2" smd rect
			(at -0.40005 0 270)
			(size 0.4572 0.508)
			(layers "F.Cu" "F.Mask" "F.Paste")
			(net "T6_NODE4_EN_R")
		)
	)
	(footprint ""
		(layer "F.Cu")
		(at 125.735588 -181.503828 180)
		(property "Reference" "R721"
			(at -1.520444 -1.289304 0)
			(unlocked yes)
			(layer "F.SilkS")
			(effects
				(font
					(size 0.7874 0.5842)
					(thickness 0.1524)
				)
				(justify left)
			)
		)
		(property "Value" ""
			(at 0 0 180)
			(layer "F.Fab")
			(effects
				(font
					(size 1.27 1.27)
				)
			)
		)
		(duplicate_pad_numbers_are_jumpers no)
		(fp_line
			(start 0.7874 0.4064)
			(end -0.7874 0.4064)
			(stroke
				(width 0.1524)
				(type default)
			)
			(layer "F.SilkS")
		)
		(fp_line
			(start 0.7874 -0.4064)
			(end 0.7874 0.4064)
			(stroke
				(width 0.1524)
				(type default)
			)
			(layer "F.SilkS")
		)
		(fp_line
			(start -0.7874 0.4064)
			(end -0.7874 -0.4064)
			(stroke
				(width 0.1524)
				(type default)
			)
			(layer "F.SilkS")
		)
		(fp_line
			(start -0.7874 -0.4064)
			(end 0.7874 -0.4064)
			(stroke
				(width 0.1524)
				(type default)
			)
			(layer "F.SilkS")
		)
		(fp_poly
			(pts
				(xy -0.508 0.2794) (xy -0.508 0.2286) (xy -0.635 0.2286) (xy -0.635 -0.254) (xy -0.5334 -0.254)
				(xy -0.5334 -0.2794) (xy 0.5334 -0.2794) (xy 0.5334 -0.254) (xy 0.635 -0.254) (xy 0.635 0.254) (xy 0.5334 0.254)
				(xy 0.5334 0.2794)
			)
			(stroke
				(width 0)
				(type default)
			)
			(fill no)
			(layer "F.CrtYd")
		)
		(pad "1" smd rect
			(at 0.40005 0 180)
			(size 0.4572 0.508)
			(layers "F.Cu" "F.Mask" "F.Paste")
			(net "T7_NODE2_EN")
		)
		(pad "2" smd rect
			(at -0.40005 0 180)
			(size 0.4572 0.508)
			(layers "F.Cu" "F.Mask" "F.Paste")
			(net "P5V_NODE1")
		)
	)
	(footprint ""
		(layer "F.Cu")
		(at 136.310878 -51.45151 -90)
		(property "Reference" "R1157"
			(at -16.29029 -30.644592 90)
			(unlocked yes)
			(layer "F.SilkS")
			(effects
				(font
					(size 0.7874 0.5842)
					(thickness 0.1524)
				)
				(justify left)
			)
		)
		(property "Value" ""
			(at 0 0 270)
			(layer "F.Fab")
			(effects
				(font
					(size 1.27 1.27)
				)
			)
		)
		(duplicate_pad_numbers_are_jumpers no)
		(fp_line
			(start -0.7874 0.4064)
			(end -0.7874 -0.4064)
			(stroke
				(width 0.1524)
				(type default)
			)
			(layer "F.SilkS")
		)
		(fp_line
			(start 0.7874 0.4064)
			(end -0.7874 0.4064)
			(stroke
				(width 0.1524)
				(type default)
			)
			(layer "F.SilkS")
		)
		(fp_line
			(start -0.7874 -0.4064)
			(end 0.7874 -0.4064)
			(stroke
				(width 0.1524)
				(type default)
			)
			(layer "F.SilkS")
		)
		(fp_line
			(start 0.7874 -0.4064)
			(end 0.7874 0.4064)
			(stroke
				(width 0.1524)
				(type default)
			)
			(layer "F.SilkS")
		)
		(fp_poly
			(pts
				(xy -0.508 0.2794) (xy -0.508 0.2286) (xy -0.635 0.2286) (xy -0.635 -0.254) (xy -0.5334 -0.254)
				(xy -0.5334 -0.2794) (xy 0.5334 -0.2794) (xy 0.5334 -0.254) (xy 0.635 -0.254) (xy 0.635 0.254) (xy 0.5334 0.254)
				(xy 0.5334 0.2794)
			)
			(stroke
				(width 0)
				(type default)
			)
			(fill no)
			(layer "F.CrtYd")
		)
		(pad "1" smd rect
			(at 0.40005 0 270)
			(size 0.4572 0.508)
			(layers "F.Cu" "F.Mask" "F.Paste")
			(net "UART_RTS_P3_R_N")
		)
		(pad "2" smd rect
			(at -0.40005 0 270)
			(size 0.4572 0.508)
			(layers "F.Cu" "F.Mask" "F.Paste")
			(net "UART_RTS_P3_N")
		)
	)
	(footprint ""
		(layer "F.Cu")
		(at 85.411818 -145.059908 -90)
		(property "Reference" "C837"
			(at 1.701038 -2.218944 90)
			(unlocked yes)
			(layer "F.SilkS")
			(effects
				(font
					(size 0.7874 0.5842)
					(thickness 0.1524)
				)
				(justify left)
			)
		)
		(property "Value" ""
			(at 0 0 270)
			(layer "F.Fab")
			(effects
				(font
					(size 1.27 1.27)
				)
			)
		)
		(duplicate_pad_numbers_are_jumpers no)
		(fp_line
			(start -0.7874 0.4064)
			(end -0.7874 -0.4064)
			(stroke
				(width 0.1524)
				(type default)
			)
			(layer "F.SilkS")
		)
		(fp_line
			(start 0.7874 0.4064)
			(end -0.7874 0.4064)
			(stroke
				(width 0.1524)
				(type default)
			)
			(layer "F.SilkS")
		)
		(fp_line
			(start 0 0.381)
			(end 0 -0.381)
			(stroke
				(width 0.1524)
				(type default)
			)
			(layer "F.SilkS")
		)
		(fp_line
			(start -0.7874 -0.4064)
			(end 0.7874 -0.4064)
			(stroke
				(width 0.1524)
				(type default)
			)
			(layer "F.SilkS")
		)
		(fp_line
			(start 0.7874 -0.4064)
			(end 0.7874 0.4064)
			(stroke
				(width 0.1524)
				(type default)
			)
			(layer "F.SilkS")
		)
		(fp_poly
			(pts
				(xy -0.5334 0.254) (xy -0.635 0.254) (xy -0.635 0.2286) (xy -0.635 -0.254) (xy -0.5334 -0.254) (xy -0.5334 -0.2794)
				(xy 0.5334 -0.2794) (xy 0.5334 -0.254) (xy 0.635 -0.254) (xy 0.635 0.254) (xy 0.5334 0.254) (xy 0.5334 0.2794)
				(xy -0.508 0.2794) (xy -0.5334 0.2794)
			)
			(stroke
				(width 0)
				(type default)
			)
			(fill no)
			(layer "F.CrtYd")
		)
		(pad "1" smd rect
			(at 0.40005 0 270)
			(size 0.4572 0.508)
			(layers "F.Cu" "F.Mask" "F.Paste")
			(net "FM_CPLD_NODE1_P1V26_BMC_EN")
		)
		(pad "2" smd rect
			(at -0.40005 0 270)
			(size 0.4572 0.508)
			(layers "F.Cu" "F.Mask" "F.Paste")
			(net "GND")
		)
	)
	(footprint ""
		(layer "F.Cu")
		(at 51.310286 -120.460262)
		(property "Reference" "C246"
			(at -7.234428 0.25146 0)
			(unlocked yes)
			(layer "F.SilkS")
			(effects
				(font
					(size 0.7874 0.5842)
					(thickness 0.1524)
				)
				(justify left)
			)
		)
		(property "Value" ""
			(at 0 0 0)
			(layer "F.Fab")
			(effects
				(font
					(size 1.27 1.27)
				)
			)
		)
		(duplicate_pad_numbers_are_jumpers no)
		(fp_line
			(start -0.7874 -0.4064)
			(end 0.7874 -0.4064)
			(stroke
				(width 0.1524)
				(type default)
			)
			(layer "F.SilkS")
		)
		(fp_line
			(start -0.7874 0.4064)
			(end -0.7874 -0.4064)
			(stroke
				(width 0.1524)
				(type default)
			)
			(layer "F.SilkS")
		)
		(fp_line
			(start 0 0.381)
			(end 0 -0.381)
			(stroke
				(width 0.1524)
				(type default)
			)
			(layer "F.SilkS")
		)
		(fp_line
			(start 0.7874 -0.4064)
			(end 0.7874 0.4064)
			(stroke
				(width 0.1524)
				(type default)
			)
			(layer "F.SilkS")
		)
		(fp_line
			(start 0.7874 0.4064)
			(end -0.7874 0.4064)
			(stroke
				(width 0.1524)
				(type default)
			)
			(layer "F.SilkS")
		)
		(fp_poly
			(pts
				(xy -0.5334 0.254) (xy -0.635 0.254) (xy -0.635 0.2286) (xy -0.635 -0.254) (xy -0.5334 -0.254) (xy -0.5334 -0.2794)
				(xy 0.5334 -0.2794) (xy 0.5334 -0.254) (xy 0.635 -0.254) (xy 0.635 0.254) (xy 0.5334 0.254) (xy 0.5334 0.2794)
				(xy -0.508 0.2794) (xy -0.5334 0.2794)
			)
			(stroke
				(width 0)
				(type default)
			)
			(fill no)
			(layer "F.CrtYd")
		)
		(pad "1" smd rect
			(at 0.40005 0)
			(size 0.4572 0.508)
			(layers "F.Cu" "F.Mask" "F.Paste")
			(net "BMC_NODE1_OSC1_VDD")
		)
		(pad "2" smd rect
			(at -0.40005 0)
			(size 0.4572 0.508)
			(layers "F.Cu" "F.Mask" "F.Paste")
			(net "GND")
		)
	)
	(footprint ""
		(layer "F.Cu")
		(at 125.735588 -179.471828 180)
		(property "Reference" "R723"
			(at -1.39446 2.707132 0)
			(unlocked yes)
			(layer "F.SilkS")
			(effects
				(font
					(size 0.7874 0.5842)
					(thickness 0.1524)
				)
				(justify left)
			)
		)
		(property "Value" ""
			(at 0 0 180)
			(layer "F.Fab")
			(effects
				(font
					(size 1.27 1.27)
				)
			)
		)
		(duplicate_pad_numbers_are_jumpers no)
		(fp_line
			(start 0.7874 0.4064)
			(end -0.7874 0.4064)
			(stroke
				(width 0.1524)
				(type default)
			)
			(layer "F.SilkS")
		)
		(fp_line
			(start 0.7874 -0.4064)
			(end 0.7874 0.4064)
			(stroke
				(width 0.1524)
				(type default)
			)
			(layer "F.SilkS")
		)
		(fp_line
			(start -0.7874 0.4064)
			(end -0.7874 -0.4064)
			(stroke
				(width 0.1524)
				(type default)
			)
			(layer "F.SilkS")
		)
		(fp_line
			(start -0.7874 -0.4064)
			(end 0.7874 -0.4064)
			(stroke
				(width 0.1524)
				(type default)
			)
			(layer "F.SilkS")
		)
		(fp_poly
			(pts
				(xy -0.508 0.2794) (xy -0.508 0.2286) (xy -0.635 0.2286) (xy -0.635 -0.254) (xy -0.5334 -0.254)
				(xy -0.5334 -0.2794) (xy 0.5334 -0.2794) (xy 0.5334 -0.254) (xy 0.635 -0.254) (xy 0.635 0.254) (xy 0.5334 0.254)
				(xy 0.5334 0.2794)
			)
			(stroke
				(width 0)
				(type default)
			)
			(fill no)
			(layer "F.CrtYd")
		)
		(pad "1" smd rect
			(at 0.40005 0 180)
			(size 0.4572 0.508)
			(layers "F.Cu" "F.Mask" "F.Paste")
			(net "T7_NODE4_EN")
		)
		(pad "2" smd rect
			(at -0.40005 0 180)
			(size 0.4572 0.508)
			(layers "F.Cu" "F.Mask" "F.Paste")
			(net "P5V_NODE1")
		)
	)
)
